# BASEBOARD_FAB2 (Tioga Pass) — schematic netlist excerpt (pin names and nets, part order shuffled) for the footprints in the layout excerpt that follows; sources: Cadence DE-HDL packaged netlist, KiCad conversion of Wiwynn_Tioga_Pass_MB.brd

RT19  RES  0 5.0% CHIP  pkg 0603  page 224 : A = VR_PVDDQ_GHJ_PH1_BOOT ; B = VR_PVDDQ_GHJ_PH1_BOOT_R
R8C1  RES  4.75K 1% CHIP  pkg 0402  page 133 : A = P3V3_STBY ; B = FM_SLT_CFG1

(kicad_pcb
	(version 20260206)
	(generator "pcbnew")
	(generator_version "10.0")
	(general
		(thickness 1.6)
		(legacy_teardrops no)
	)
	(paper "A4")
	(title_block
		(title "Wiwynn_Tioga_Pass_MB.brd")
		(comment 1 "Tioga Pass / footprints 523-524 of 4770")
	)
	(layers
		(0 "F.Cu" signal "TOP")
		(4 "In1.Cu" signal "L2GND")
		(6 "In2.Cu" signal "L3")
		(8 "In3.Cu" signal "L4GND")
		(10 "In4.Cu" signal "L5")
		(12 "In5.Cu" signal "L6GND")
		(14 "In6.Cu" signal "L7VCC")
		(16 "In7.Cu" signal "L8VCC")
		(18 "In8.Cu" signal "L9GND")
		(20 "In9.Cu" signal "L10")
		(22 "In10.Cu" signal "L11GND")
		(24 "In11.Cu" signal "L12")
		(26 "In12.Cu" signal "L13GND")
		(2 "B.Cu" signal "BOTTOM")
		(9 "F.Adhes" user "F.Adhesive")
		(11 "B.Adhes" user "B.Adhesive")
		(13 "F.Paste" user "Package Geometry/Pastemask Top")
		(15 "B.Paste" user "Package Geometry/Pastemask Bottom")
		(5 "F.SilkS" user "Ref Des/Silkscreen Top")
		(7 "B.SilkS" user "Ref Des/Silkscreen Bottom")
		(1 "F.Mask" user "Board Geometry/Soldermask Top")
		(3 "B.Mask" user "Board Geometry/Soldermask Bottom")
		(17 "Dwgs.User" user "User.Drawings")
		(19 "Cmts.User" user "User.Comments")
		(21 "Eco1.User" user "User.Eco1")
		(23 "Eco2.User" user "User.Eco2")
		(25 "Edge.Cuts" user "Board Geometry/Outline")
		(27 "Margin" user)
		(31 "F.CrtYd" user "Package Geometry/Place Bound Top")
		(29 "B.CrtYd" user "Package Geometry/Place Bound Bottom")
		(35 "F.Fab" user "Ref Des/Assembly Top")
		(33 "B.Fab" user "Ref Des/Assembly Bottom")
	)
	(footprint ""
		(layer "F.Cu")
		(at 0.74676 -11.99896)
		(property "Reference" "RT19"
			(at 1.01473 0.656336 270)
			(unlocked yes)
			(layer "F.SilkS")
			(effects
				(font
					(size 0.4064 0.254)
					(thickness 0.1524)
				)
			)
		)
		(property "Value" ""
			(at 0 0 0)
			(layer "F.Fab")
			(effects
				(font
					(size 1.27 1.27)
				)
			)
		)
		(duplicate_pad_numbers_are_jumpers no)
		(fp_rect
			(start -0.4953 1.6002)
			(end 0.4953 -0.2032)
			(stroke
				(width 0)
				(type default)
			)
			(fill no)
			(layer "F.CrtYd")
		)
		(fp_line
			(start -0.4953 -0.2032)
			(end 0.4953 -0.2032)
			(stroke
				(width 0.1)
				(type default)
			)
			(layer "F.Fab")
		)
		(fp_line
			(start -0.4953 1.6002)
			(end -0.4953 -0.2032)
			(stroke
				(width 0.1)
				(type default)
			)
			(layer "F.Fab")
		)
		(fp_line
			(start 0.4953 -0.2032)
			(end 0.4953 1.6002)
			(stroke
				(width 0.1)
				(type default)
			)
			(layer "F.Fab")
		)
		(fp_line
			(start 0.4953 1.6002)
			(end -0.4953 1.6002)
			(stroke
				(width 0.1)
				(type default)
			)
			(layer "F.Fab")
		)
		(pad "1" smd rect
			(at 0 0)
			(size 0.762 0.889)
			(layers "F.Cu" "F.Mask" "F.Paste")
			(net "VR_PVDDQ_GHJ_PH1_BOOT")
		)
		(pad "2" smd rect
			(at 0 1.397)
			(size 0.762 0.889)
			(layers "F.Cu" "F.Mask" "F.Paste")
			(net "VR_PVDDQ_GHJ_PH1_BOOT_R")
		)
		(zone
			(layer "F.Cu")
			(hatch none 0.5)
			(connect_pads
				(clearance 0)
			)
			(min_thickness 0.25)
			(keepout
				(tracks not_allowed)
				(vias allowed)
				(pads allowed)
				(copperpour not_allowed)
				(footprints allowed)
			)
			(placement
				(enabled no)
				(sheetname "")
			)
			(fill
				(thermal_gap 0.5)
				(thermal_bridge_width 0.5)
				(island_removal_mode 0)
			)
			(polygon
				(pts
					(xy 0.36576 -11.04646) (xy 1.12776 -11.04646) (xy 1.12776 -11.55446) (xy 0.36576 -11.55446)
				)
			)
		)
		(zone
			(layer "F.Cu")
			(hatch none 0.5)
			(connect_pads
				(clearance 0)
			)
			(min_thickness 0.25)
			(keepout
				(tracks allowed)
				(vias not_allowed)
				(pads allowed)
				(copperpour not_allowed)
				(footprints allowed)
			)
			(placement
				(enabled no)
				(sheetname "")
			)
			(fill
				(thermal_gap 0.5)
				(thermal_bridge_width 0.5)
				(island_removal_mode 0)
			)
			(polygon
				(pts
					(xy 0.36576 -11.04646) (xy 1.12776 -11.04646) (xy 1.12776 -11.55446) (xy 0.36576 -11.55446)
				)
			)
		)
	)
	(footprint ""
		(layer "F.Cu")
		(at 411.0355 -111.633 -90)
		(property "Reference" "R8C1"
			(at 0 0 270)
			(layer "F.SilkS")
			(hide yes)
			(effects
				(font
					(size 1.27 1.27)
				)
			)
		)
		(property "Value" ""
			(at 0 0 270)
			(layer "F.Fab")
			(effects
				(font
					(size 1.27 1.27)
				)
			)
		)
		(duplicate_pad_numbers_are_jumpers no)
		(fp_poly
			(pts
				(xy -0.2794 -0.1016) (xy 0.2794 -0.1016) (xy 0.2794 0.9906) (xy -0.2794 0.9906)
			)
			(stroke
				(width 0)
				(type default)
			)
			(fill no)
			(layer "F.CrtYd")
		)
		(fp_line
			(start -0.2794 0.9906)
			(end 0.2794 0.9906)
			(stroke
				(width 0.1)
				(type default)
			)
			(layer "F.Fab")
		)
		(fp_line
			(start 0.2794 0.9906)
			(end 0.2794 -0.1016)
			(stroke
				(width 0.1)
				(type default)
			)
			(layer "F.Fab")
		)
		(fp_line
			(start -0.2794 -0.1016)
			(end -0.2794 0.9906)
			(stroke
				(width 0.1)
				(type default)
			)
			(layer "F.Fab")
		)
		(fp_line
			(start 0.2794 -0.1016)
			(end -0.2794 -0.1016)
			(stroke
				(width 0.1)
				(type default)
			)
			(layer "F.Fab")
		)
		(pad "1" smd rect
			(at 0 0 270)
			(size 0.508 0.508)
			(layers "F.Cu" "F.Mask" "F.Paste")
			(net "P3V3_STBY")
		)
		(pad "2" smd rect
			(at 0 0.889 270)
			(size 0.508 0.508)
			(layers "F.Cu" "F.Mask" "F.Paste")
			(net "FM_SLT_CFG1")
		)
		(zone
			(layer "F.Cu")
			(hatch none 0.5)
			(connect_pads
				(clearance 0)
			)
			(min_thickness 0.25)
			(keepout
				(tracks not_allowed)
				(vias allowed)
				(pads allowed)
				(copperpour not_allowed)
				(footprints allowed)
			)
			(placement
				(enabled no)
				(sheetname "")
			)
			(fill
				(thermal_gap 0.5)
				(thermal_bridge_width 0.5)
				(island_removal_mode 0)
			)
			(polygon
				(pts
					(xy 410.4005 -111.887) (xy 410.4005 -111.379) (xy 410.7815 -111.379) (xy 410.7815 -111.887)
				)
			)
		)
		(zone
			(layer "F.Cu")
			(hatch none 0.5)
			(connect_pads
				(clearance 0)
			)
			(min_thickness 0.25)
			(keepout
				(tracks allowed)
				(vias not_allowed)
				(pads allowed)
				(copperpour not_allowed)
				(footprints allowed)
			)
			(placement
				(enabled no)
				(sheetname "")
			)
			(fill
				(thermal_gap 0.5)
				(thermal_bridge_width 0.5)
				(island_removal_mode 0)
			)
			(polygon
				(pts
					(xy 410.7815 -111.887) (xy 410.7815 -111.379) (xy 410.4005 -111.379) (xy 410.4005 -111.887)
				)
			)
		)
	)
)
